# S9S_MB_2U (Grand Teton) — schematic parts with pin connectivity, parts 5895–5926 of 6093; source: Cadence DE-HDL packaged netlist (pstxprt.dat, pstxnet.dat, pstchip.dat)

U29  PCA9617ADP  IC  pkg TSSOP8_3XB  page 235
  1  VCCA  POWER  = PVNN_TERM_CPU1
  2  SCLA  BI  = SMB_PEHPCPU1_GTL_R_SCL
  3  SDAA  BI  = SMB_PEHPCPU1_GTL_R_SDA
  4  GND  POWER  = GND
  5  EN  IN  = TP_SMB_PEHPCPU1_EN
  6  SDAB  BI  = SMB_PEHPCPU1_LVC3_SDA_R0
  7  SCLB  BI  = SMB_PEHPCPU1_LVC3_SCL_R0
  8  VCCB  POWER  = P3V3_AUX

U30  PCA9517AD  IC  pkg SOIC8  page 236
  1  VCCA  POWER  = PVNN_TERM_CPU0
  2  SCLA  BI  = SMB_S3M_CPU0_R_SCL
  3  SDAA  BI  = SMB_S3M_CPU0_R_SDA
  4  GND  POWER  = GND
  5  ENABLE  BI  = TP_SMB_S3M_CPU0_EN
  6  SDAB  BI  = SMB_S3M_CPU0_3V3AUX_SDA
  7  SCLB  BI  = SMB_S3M_CPU0_3V3AUX_SCL
  8  VCCB  BI  = P3V3_AUX

U31  PCA9517AD  IC  pkg SOIC8  page 236
  1  VCCA  POWER  = PVNN_TERM_CPU1
  2  SCLA  BI  = SMB_S3M_CPU1_R_SCL
  3  SDAA  BI  = SMB_S3M_CPU1_R_SDA
  4  GND  POWER  = GND
  5  ENABLE  BI  = TP_SMB_S3M_CPU1_EN
  6  SDAB  BI  = SMB_S3M_CPU1_3V3AUX_SDA
  7  SCLB  BI  = SMB_S3M_CPU1_3V3AUX_SCL
  8  VCCB  BI  = P3V3_AUX

U36  TCA9548APWR  IC  pkg TSSOP24XA  page 231
  1  A0  IN  = PCA9548_PCIE3_ADDR0
  2  A1  IN  = PCA9548_PCIE3_ADDR1
  3  \reset#\  IN  = PU_RST_SMB_PCIE0_N
  4  SD0  BI  = NC
  5  SC0  BI  = NC
  6  SD1  BI  = SMB_IOEXP_3V3AUX_SDA_R
  7  SC1  BI  = SMB_IOEXP_3V3AUX_SCL_R
  8  SD2  BI  = SMB_PCIE0_3V3AUX_SDA_R3
  9  SC2  BI  = SMB_PCIE0_3V3AUX_SCL_R3
  10  SD3  BI  = SMB_PCIE0_3V3AUX_SDA_R5
  11  SC3  BI  = SMB_PCIE0_3V3AUX_SCL_R5
  12  GND  POWER  = GND
  13  SD4  BI  = SMB_BMC_SWB_SDA_R4
  14  SC4  BI  = SMB_BMC_SWB_SCL_R4
  15  SD5  BI  = SMB_FRU_3V3AUX_SDA_R
  16  SC5  BI  = SMB_FRU_3V3AUX_SCL_R
  17  SD6  BI  = SMB_INA230_3V3AUX_SDA_R
  18  SC6  BI  = SMB_INA230_3V3AUX_SCL_R
  19  SD7  BI  = NC
  20  SC7  BI  = NC
  21  A2  IN  = PCA9548_PCIE3_ADDR2
  22  SCL  BI  = SMB_PCIE0_3V3AUX_SCL_R
  23  SDA  BI  = SMB_PCIE0_3V3AUX_SDA_R
  24  VCC  POWER  = P3V3_AUX

U38  9QXL2001BNHGI8  IC  pkg GQFN80_TH_0-5_6X6  page 206
  A1  DIF17  OUT  = CLK_100M_OCP_V3_2_D_R_DP
  A2  \dif16#\  OUT  = CLK_100M_OCP_V3_2_C_R_DN
  A3  DIF16  OUT  = CLK_100M_OCP_V3_2_C_R_DP
  A4  \dif15#\  OUT  = CLK_100M_OCP_V3_2_B_R_DN
  A5  DIF15  OUT  = CLK_100M_OCP_V3_2_B_R_DP
  A6  \dif14#\  OUT  = CLK_100M_OCP_V3_2_A_R_DN
  A7  DIF14  OUT  = CLK_100M_OCP_V3_2_A_R_DP
  A8  \dif13#\  OUT  = TP_CLK_100M_DIF13_DN
  A9  DIF13  OUT  = TP_CLK_100M_DIF13_DP
  A10  \dif12#\  OUT  = CLK_100M_OCP_SFF_3_R_DN
  A11  DIF12  OUT  = CLK_100M_OCP_SFF_3_R_DP
  A12  \dif11#\  OUT  = CLK_100M_OCP_SFF_2_R_DN
  B1  \dif17#\  OUT  = CLK_100M_OCP_V3_2_D_R_DN
  B2  \vddo3.3_b2\  POWER  = P3V3_DB2000_VDD
  B3  NC1  TRI  = NC_CLK_100M_DB2000_NC1
  B4  \^vsadr0_tri\  IN  = PD_DB2000_SMB_SA0
  B5  NC2  TRI  = NC_CLK_100M_DB2000_NC2
  B6  \vdda3.3\  POWER  = P3V3_DB2000_VDDA
  B7  NC3  TRI  = NC_CLK_100M_DB2000_NC3
  B8  \^vsadr1_tri\  IN  = PD_DB2000_SMB_SA1
  B9  NC4  TRI  = NC_CLK_100M_DB2000_NC4
  B10  \voe12#\  IN  = FM_DB2000_12_OE_N
  B11  \vddo3.3_b11\  POWER  = P3V3_DB2000_VDD
  B12  DIF11  OUT  = CLK_100M_OCP_SFF_2_R_DP
  C1  DIF18  OUT  = TP_CLK_100M_DIF18_DP
  C2  NC5  TRI  = NC_CLK_100M_DB2000_NC5
  C11  \voe11#\  IN  = FM_DB2000_11_OE_N
  C12  \dif10#\  OUT  = CLK_100M_OCP_SFF_1_R_DN
  D1  \dif18#\  OUT  = TP_CLK_100M_DIF18_DN
  D2  NC6  TRI  = NC_CLK_100M_DB2000_NC6
  D11  NC7  TRI  = NC_CLK_100M_DB2000_NC7
  D12  DIF10  OUT  = CLK_100M_OCP_SFF_1_R_DP
  E1  DIF19  OUT  = TP_CLK_100M_DIF19_DP
  E2  VSBEN  IN  = FM_DB2000_VSBEN
  E11  \voe10#||shft_ld#\  IN  = FM_DB2000_10_OE_N
  E12  \voe9#\  IN  = FM_DB2000_9_OE_N
  F1  \dif19#\  OUT  = TP_CLK_100M_DIF19_DN
  F2  NC8  TRI  = NC_CLK_100M_DB2000_NC8
  F11  NC9  TRI  = NC_CLK_100M_DB2000_NC9
  F12  \dif9#\  OUT  = CLK_100M_OCP_SFF_0_R_DN
  G1  DIF_IN  IN  = CLK_100M_DB2000_DP
  G2  NC10  TRI  = NC_CLK_100M_DB2000_NC10
  G11  NC11  TRI  = NC_CLK_100M_DB2000_NC11
  G12  DIF9  OUT  = CLK_100M_OCP_SFF_0_R_DP
  H1  \dif_in#\  IN  = CLK_100M_DB2000_DN
  H2  \vddr3.3\  POWER  = P3V3_DB2000_VDDR
  H11  \voe8#\  IN  = FM_DB2000_8_OE_N
  H12  \dif8#\  OUT  = CLK_100M_GPU_SWB_REF_DN
  J1  DIF0  OUT  = CLK_100M_DB2000_CPU0_BCLK0_DP
  J2  NC12  TRI  = NC_CLK_100M_DB2000_NC12
  J11  NC13  TRI  = NC_CLK_100M_DB2000_NC13
  J12  DIF8  OUT  = CLK_100M_GPU_SWB_REF_DP
  K1  \dif0#\  OUT  = CLK_100M_DB2000_CPU0_BCLK0_DN
  K2  NC14  TRI  = NC_CLK_100M_DB2000_NC14
  K11  \voe7#\  IN  = FM_DB2000_1_OE_N
  K12  \dif7#\  OUT  = CLK_100M_DB2000_CPU1_BCLK3_DN
  L1  DIF1  OUT  = CLK_100M_DB2000_CPU0_BCLK1_DP
  L2  \vddo3.3_l2\  POWER  = P3V3_DB2000_VDD
  L3  NC17  TRI  = NC_CLK_100M_DB2000_NC17
  L4  SMBDAT  BI  = SMB_HOST_DB2000_3V3AUX_SDA
  L5  SMBCLK  IN  = SMB_HOST_DB2000_3V3AUX_SCL
  L6  NC15  TRI  = NC_CLK_100M_DB2000_NC15
  L7  NC16  TRI  = NC_CLK_100M_DB2000_NC16
  L8  \voe5#||data\  IN  = FM_DB2000_1_OE_N
  L9  NC18  TRI  = NC_CLK_100M_DB2000_NC18
  L10  \voe6#||clk\  IN  = FM_DB2000_1_OE_N
  L11  \vddo3.3_l11\  POWER  = P3V3_DB2000_VDD
  L12  DIF7  OUT  = CLK_100M_DB2000_CPU1_BCLK3_DP
  M1  \dif1#\  OUT  = CLK_100M_DB2000_CPU0_BCLK1_DN
  M2  DIF2  OUT  = CLK_100M_DB2000_CPU0_BCLK2_DP
  M3  \dif2#\  OUT  = CLK_100M_DB2000_CPU0_BCLK2_DN
  M4  DIF3  OUT  = CLK_100M_DB2000_CPU0_BCLK3_DP
  M5  \dif3#\  OUT  = CLK_100M_DB2000_CPU0_BCLK3_DN
  M6  \vckpwrgd_pd#\  IN  = FM_DB2000_DEV_EN
  M7  DIF4  OUT  = CLK_100M_DB2000_CPU1_BCLK0_DP
  M8  \dif4#\  OUT  = CLK_100M_DB2000_CPU1_BCLK0_DN
  M9  DIF5  OUT  = CLK_100M_DB2000_CPU1_BCLK1_DP
  M10  \dif5#\  OUT  = CLK_100M_DB2000_CPU1_BCLK1_DN
  M11  DIF6  OUT  = CLK_100M_DB2000_CPU1_BCLK2_DP
  M12  \dif6#\  OUT  = CLK_100M_DB2000_CPU1_BCLK2_DN
  TH  EPAD  POWER  = GND

U39  TCA9548APWR  IC  pkg TSSOP24XA  page 233
  1  A0  IN  = PCA9548_PCIE0_ADDR0
  2  A1  IN  = PCA9548_PCIE0_ADDR1
  3  \reset#\  IN  = PU_RST_SMB_PCIE2_N
  4  SD0  BI  = SMB_VR_3V3AUX_SDA_R6
  5  SC0  BI  = SMB_VR_3V3AUX_SCL_R6
  6  SD1  BI  = SMB_LM75_0_3V3AUX_SDA_R
  7  SC1  BI  = SMB_LM75_0_3V3AUX_SCL_R
  8  SD2  BI  = SMB_LM75_1_3V3AUX_SDA_R
  9  SC2  BI  = SMB_LM75_1_3V3AUX_SCL_R
  10  SD3  BI  = SMB_LM75_2_3V3AUX_SDA_R
  11  SC3  BI  = SMB_LM75_2_3V3AUX_SCL_R
  12  GND  POWER  = GND
  13  SD4  BI  = SMB_LM75_3_3V3AUX_SDA_R
  14  SC4  BI  = SMB_LM75_3_3V3AUX_SCL_R
  15  SD5  BI  = NC
  16  SC5  BI  = NC
  17  SD6  BI  = NC
  18  SC6  BI  = NC
  19  SD7  BI  = NC
  20  SC7  BI  = NC
  21  A2  IN  = PCA9548_PCIE0_ADDR2
  22  SCL  BI  = SMB_VR_SENSOR_3V3AUX_SCL_R
  23  SDA  BI  = SMB_VR_SENSOR_3V3AUX_SDA_R
  24  VCC  POWER  = P3V3_AUX

U49  MOSFET_N  BSS138K IC  pkg SMLF  page 158
  D  DRAIN  OUT  = HP_LVC3_OCP_V3_1_PRSNT2
  G  GATE  IN  = HP_LVC3_OCP_V3_1_PRSNT2_N
  S  SOURCE  BI  = GND

U50  74LVC1G08W57  74LVC1G08W5-7 IC  pkg SOT25-5_0-95_3X1-6  page 164
  1  A  IN  = HP_OCP_V3_2_EN
  2  B  IN  = HP_LVC3_OCP_V3_2_PRSNT2
  3  GND  POWER  = GND
  4  Y  OUT  = HP_LVC3_OCP_V3_2_EN
  5  VCC  POWER  = P3V3_AUX

U51  PCA9555APW  IC  pkg TSSOP24XB  page 164
  1  \int#\  OUT  = FM_SMB_CPU1_ALERT
  2  A1  IN  = PD_SMB_OCP2_HP_ADD1
  3  A2  IN  = PD_SMB_OCP2_HP_ADD2
  4  P0_0  BI  = TP_PCA9555_U51_P00
  5  P0_1  BI  = TP_PCA9555_U51_P01
  6  P0_2  BI  = HP_OCP_V3_2_EN
  7  P0_3  BI  = HP_LVC3_OCP_V3_2_ATTN_OUT_SW_N
  8  P0_4  BI  = HP_LVC3_OCP_V3_2_PRSNT2_N
  9  P0_5  BI  = TP_PCA9555_U51_P05
  10  P0_6  BI  = TP_PCA9555_U51_P06
  11  P0_7  BI  = TP_PCA9555_U51_P07
  12  VSS  POWER  = GND
  13  P1_0  BI  = TP_PCA9555_U51_P10
  14  P1_1  BI  = TP_PCA9555_U51_P11
  15  P1_2  BI  = TP_PCA9555_U51_P12
  16  P1_3  BI  = TP_PCA9555_U51_P13
  17  P1_4  BI  = TP_PCA9555_U51_P14
  18  P1_5  BI  = TP_PCA9555_U51_P15
  19  P1_6  BI  = TP_PCA9555_U51_P16
  20  P1_7  BI  = TP_PCA9555_U51_P17
  21  A0  IN  = PD_SMB_OCP2_HP_ADD0
  22  SCL  IN  = SMB_PEHPCPU1_LVC3_R3_SCL
  23  SDA  BI  = SMB_PEHPCPU1_LVC3_R3_SDA
  24  VDD  POWER  = P3V3_AUX

U52  APX80929SAG7  APX809-29SAG-7 IC  pkg SOT23_123XI  page 158
  1  GND  POWER  = GND
  2  RESET_L  OUT  = HP_OCP_V3_1_RST
  3  VCC  POWER  = P3V3_OCP_SFF

U53  74LVC1G08W57  74LVC1G08W5-7 IC  pkg SOT25-5_0-95_3X1-6  page 164
  1  A  IN  = HP_LVC3_OCP_V3_2_PWRGD_R
  2  B  IN  = RST_OCP_V3_2_N
  3  GND  POWER  = GND
  4  Y  OUT  = RST_HP_OCP_V3_2_N
  5  VCC  POWER  = P3V3_AUX

U58  74LVC2G07DW7  74LVC2G07DW-7 IC  pkg SOT363_0-65_2X1-25XC  page 162
  1  \1a\  IN  = OCP_V3_2_PRSNT0_R_N
  2  GND  POWER  = GND
  3  \2a\  IN  = OCP_V3_2_PRSNT1_R_N
  4  \2y\  OUT  = HP_LVC3_OCP_V3_2_PRSNT2_N_R
  5  VCC  POWER  = P3V3_AUX
  6  \1y\  OUT  = HP_LVC3_OCP_V3_2_PRSNT2_N_R

U59  74LVC2G07DW7  74LVC2G07DW-7 IC  pkg SOT363_0-65_2X1-25XC  page 162
  1  \1a\  IN  = OCP_V3_2_PRSNT2_R_N
  2  GND  POWER  = GND
  3  \2a\  IN  = OCP_V3_2_PRSNT3_R_N
  4  \2y\  OUT  = HP_LVC3_OCP_V3_2_PRSNT2_N_R
  5  VCC  POWER  = P3V3_AUX
  6  \1y\  OUT  = HP_LVC3_OCP_V3_2_PRSNT2_N_R

U60  NC7SB3157  NC7SB3157P6X IC  pkg SMLF  page 202
  1  B1  BI  = IRQ_LPC_PIRQA_N_ESPI_ALERT0_R_N
  2  GND  POWER  = GND
  3  B0  BI  = IRQ_LPC_SERIRQ_ESPI_CS1_R_N
  4  A  BI  = IRQ_ESPI_LPC_SERIRQ_ALERT_N
  5  VCC  POWER  = PGPPA_AUX
  6  S  IN  = FM_ESPI_PLD_EN

U61  NC7SB3157  NC7SB3157P6X IC  pkg SMLF  page 202
  1  B1  BI  = RST_ESPI_RESET_N_R
  2  GND  POWER  = GND
  3  B0  BI  = RST_PLTRST_B_MUX_N
  4  A  BI  = ESPI_BMC_LPC_RST_N
  5  VCC  POWER  = PGPPA_AUX
  6  S  IN  = FM_ESPI_PLD_EN

U62  BAS70057F  BAS70-05-7-F IC  pkg SOT23_123XB  page 185
  1  B  IN  = P3V_BAT_R
  2  A  IN  = P3V3_AUX
  3  C  BI  = P3V3_RTC_AUX

U64  M24128BWMN6TP  M24128-BWMN6TP IC  pkg SOIC8XH  page 243
  1  E0  IN  = MB_FRU_ADDR0
  2  E1  IN  = MB_FRU_ADDR1
  3  E2  IN  = MB_FRU_ADDR2
  4  VSS  POWER  = GND
  5  SDA  BI  = SMB_FRU_3V3AUX_SDA
  6  SCL  IN  = SMB_FRU_3V3AUX_SCL
  7  \wc#\  IN  = PD_MB_FRU_WP
  8  VCC  POWER  = P3V3_AUX

U66  74LVC1G126SE7  74LVC1G126SE-7 IC  pkg SOT353_0-65_2X1-25  page 154
  1  OE  IN  = OCP_SFF_AUX_PWR_EN_R1
  2  A  IN  = FM_OCP_SFF_PWR_GOOD
  3  GND  POWER  = GND
  4  Y  OUT  = FB_BMC_ISOLATE_R1
  5  VCC  POWER  = P3V3_AUX

U67  74CBTLV3126PW  IC  pkg TSSOP14  page 154
  1  \1oe\  IN  = FB_BMC_ISOLATE
  2  \1a\  POWER  = NCSI_BMC_RXD1_R
  3  \1b\  BI  = NCSI_OCP_SFF_RXD1
  4  \2oe\  OUT  = FB_BMC_ISOLATE
  5  \2a\  BI  = NCSI_BMC_RXD0_R
  6  \2b\  BI  = NCSI_OCP_SFF_RXD0
  7  GND  POWER  = GND
  8  \3b\  BI  = NCSI_OCP_SFF_CRS_DV
  9  \3a\  BI  = NCSI_BMC_CRS_DV_R
  10  \3oe\  BI  = FB_BMC_ISOLATE
  11  \4b\  BI  = OCP_SFF_ISO1_RBT_ARB_IN
  12  \4a\  BI  = OCP_SFF_RBT_ARB_IN_R
  13  \4oe\  BI  = FB_BMC_ISOLATE
  14  VCC  BI  = P3V3_AUX

U68  74CBTLV3126PW  IC  pkg TSSOP14  page 154
  1  \1oe\  IN  = FB_BMC_ISOLATE
  2  \1a\  POWER  = NCSI_BMC_TXD1_R
  3  \1b\  BI  = NCSI_OCP_SFF_TXD1
  4  \2oe\  OUT  = FB_BMC_ISOLATE
  5  \2a\  BI  = NCSI_BMC_TXD0_R
  6  \2b\  BI  = NCSI_OCP_SFF_TXD0
  7  GND  POWER  = GND
  8  \3b\  BI  = NCSI_OCP_SFF_TX_EN
  9  \3a\  BI  = NCSI_BMC_TX_EN_R
  10  \3oe\  BI  = FB_BMC_ISOLATE
  11  \4b\  BI  = OCP_SFF_ISO2_RBT_ARB_OUT
  12  \4a\  BI  = OCP_SFF_RBT_ARB_OUT
  13  \4oe\  BI  = FB_BMC_ISOLATE
  14  VCC  BI  = P3V3_AUX

U70  MOSFET_N  BSS138K IC  pkg SMLF  page 223
  D  DRAIN  OUT  = FM_PLD_CLKS_OE_R_N
  G  GATE  IN  = FM_PLD_CLKS_DEV_EN
  S  SOURCE  BI  = GND

U75  74LVC1G17GW  IC  pkg TSSOP5  page 155
  1  NC  TRI  = NC
  2  A  IN  = RST_HP_OCP_V3_1_N
  3  GND  POWER  = GND
  4  Y  OCA  = RST_OCP_V3_1_BUF_N
  5  VCC  POWER  = P3V3_AUX

U82  74LVC1G126SE7  74LVC1G126SE-7 IC  pkg SOT353_0-65_2X1-25  page 155
  1  OE  IN  = PU_OCP_SFF_WAKE_OE
  2  A  IN  = IRQ_LVC3_OCP_SFF_WAKE_N
  3  GND  POWER  = GND
  4  Y  OUT  = OCP_SFF_WAKE_BUFF_N
  5  VCC  POWER  = P3V3_AUX

U83  GTL2014PW  IC  pkg TSSOP14  page 239
  1  DIR  IN  = PD_GTL2014_BMC_JTAG_DIR_2
  2  B0  BI  = PD_JTAG_DBP_B0
  3  B1  BI  = JTAG_DBP_PRDY_R_N
  4  VREF  POWER  = P0V7_JTAG_VREF_2
  5  B2  BI  = PD_JTAG_DBP_B2
  6  B3  BI  = JTAG_DBP_FB_TDO
  7  GND_0  POWER  = GND
  8  GND_1  POWER  = GND
  9  A3  BI  = JTAG_BMC_DBP_TDO_R
  10  A2  BI  = TP_JTAG_BMC_A2
  11  GND_2  POWER  = GND
  12  A1  BI  = JTAG_DBP_BMC_PRDY_R1_N
  13  A0  BI  = TP_JTAG_BMC_A0
  14  VCC  POWER  = P3V3_AUX

U84  GTL2014PW  IC  pkg TSSOP14  page 239
  1  DIR  IN  = PU_GTL2014_BMC_JTAG_DIR_1
  2  B0  BI  = JTAG_DBP_PREQ_R_N
  3  B1  BI  = FM_CPU_FBRK_DEBUG_N
  4  VREF  POWER  = PD_GTL2014_BMC_JTAG_VREF_1
  5  B2  BI  = JTAG_DBP_FB_TDI
  6  B3  BI  = JTAG_DBP_FB_TMS
  7  GND_0  POWER  = GND
  8  GND_1  POWER  = GND
  9  A3  BI  = JTAG_BMC_DBP_TMS_R
  10  A2  BI  = JTAG_BMC_DBP_TDI_R
  11  GND_2  POWER  = GND
  12  A1  BI  = FM_BMC_CPU_FBRK_OUT_N
  13  A0  BI  = JTAG_DBP_BMC_PREQ_R1_N
  14  VCC  POWER  = P3V3_AUX

U85  NC7SB3157  NC7SB3157P6X IC  pkg SMLF  page 134
  1  B1  BI  = JTAG_BMC_PCH_TCK
  2  GND  POWER  = GND
  3  B0  BI  = JTAG_BMC_CPU_TCK
  4  A  BI  = JTAG_BMC_DBP_TCK
  5  VCC  POWER  = P3V3_AUX
  6  S  IN  = FM_JTAG_TCK_MUX_SEL

U86  74CBTLV3126PW  IC  pkg TSSOP14  page 134
  1  \1oe\  IN  = PD_JTAG_BMC_NTRST_N
  2  \1a\  POWER  = FM_BMC_EN_DET
  3  \1b\  BI  = TP_JTAG_BMC_1B
  4  \2oe\  OUT  = JTAG_BMC_CPU_TCK
  5  \2a\  BI  = FM_BMC_EN_DET
  6  \2b\  BI  = JTAG_DBP_CPU_GTL_TCK_R1
  7  GND  POWER  = GND
  8  \3b\  BI  = JTAG_DBP_TCK_PCH_R
  9  \3a\  BI  = FM_BMC_EN_DET
  10  \3oe\  BI  = JTAG_BMC_PCH_TCK
  11  \4b\  BI  = TP_JTAG_BMC_4B
  12  \4a\  BI  = FM_BMC_EN_DET
  13  \4oe\  BI  = PD_JTAG_BMC_NTRST_N
  14  VCC  BI  = P3V3_AUX

U87  MOSFET_N  BSS138K IC  pkg SMLF  page 134
  D  DRAIN  OUT  = P1V05_PCH_AUX
  G  GATE  IN  = FM_REMOTE_DEBUG_DET_R
  S  SOURCE  BI  = FM_BMC_EN_DET

U89  MOSFET_N  BSS138K IC  pkg SMLF  page 218
  D  DRAIN  OUT  = FM_PLD_HEARTBEAT_LVC3_D
  G  GATE  IN  = FM_PLD_HEARTBEAT_LVC3
  S  SOURCE  BI  = GND

U90  PI6CV304LE  IC  pkg TSSOP8  page 155
  1  CLK_IN  IN  = CLK_50M_RMII_R
  2  OE  IN  = CLK_50M_EN
  3  Y0  OUT  = CLK_50M_BMC_MAC_R
  4  GND  POWER  = GND
  5  Y1  OUT  = CLK_50M_NCSI_OCP_1
  6  VDD  POWER  = P3V3_AUX
  7  Y2  OUT  = CLK_50M_NCSI_OCP_2
  8  Y3  OUT  = TP_CLK_50M_PCH_LOM

U94  ADM1086AKSZREEL7  ADM1086AKSZ-REEL7 IC  pkg SC70-6_0-65_2X1-25XA  page 244
  1  ENIN  IN  = FM_COMP_P3V3_AUX_ENIN
  2  GND  POWER  = GND
  3  VIN  POWER  = FM_COMP_P3V3_AUX_VIN
  4  ENOUT  OUT  = PWRGD_DSW_PWROK_R1
  5  CEXT  BI  = FM_COMP_P3V3_STBY_CEXT
  6  VCC  POWER  = P3V3_AUX

U95  74LVC1G07SE7  74LVC1G07SE-7 IC  pkg SOT353_0-65_2X1-25  page 244
  1  NC1  TRI  = NC
  2  A  IN  = PWRGD_DSW_PWROK_R1
  3  GND  POWER  = GND
  4  Y  OUT  = PWRGD_DSW_PWROK_R2
  5  VCC  POWER  = P3V3_AUX
